0.00100 T01
0.01000 T02
0.01200 T03
0.01400 T04
0.01417 T05
0.01600 T06
0.02000 T07
0.02800 T08
0.02834 T09
0.02913 T010
0.03700 T011
0.05300 T012
0.08600 T013
0.08700 T014
0.09300 T015
0.09400 T016
0.09700 T017
0.11100 T018
0.11900 T019
0.13800 T020
0.14000 T021
0.16600 T022
0.16800 T023
0.22500 T024
0.40400 T025
